(kicad_pcb
	(version 20260206)
	(generator "pcbnew")
	(generator_version "10.0")
	(general
		(thickness 1.6)
		(legacy_teardrops no)
	)
	(paper "A4")
	(title_block
		(title "Bryce Canyon_R.DPB_16317-1_OCP.brd")
		(comment 1 "Bryce Canyon / footprints 1306-1313 of 2099")
	)
	(layers
		(0 "F.Cu" signal "TOP")
		(4 "In1.Cu" signal "L2GND")
		(6 "In2.Cu" signal "L3")
		(8 "In3.Cu" signal "L4VCC")
		(10 "In4.Cu" signal "L5VCC")
		(12 "In5.Cu" signal "L6")
		(14 "In6.Cu" signal "L7GND")
		(2 "B.Cu" signal "BOTTOM")
		(9 "F.Adhes" user "F.Adhesive")
		(11 "B.Adhes" user "B.Adhesive")
		(13 "F.Paste" user "Package Geometry/Pastemask Top")
		(15 "B.Paste" user "Package Geometry/Pastemask Bottom")
		(5 "F.SilkS" user "Ref Des/Silkscreen Top")
		(7 "B.SilkS" user "Ref Des/Silkscreen Bottom")
		(1 "F.Mask" user "Board Geometry/Soldermask Top")
		(3 "B.Mask" user "Board Geometry/Soldermask Bottom")
		(17 "Dwgs.User" user "User.Drawings")
		(19 "Cmts.User" user "User.Comments")
		(21 "Eco1.User" user "User.Eco1")
		(23 "Eco2.User" user "User.Eco2")
		(25 "Edge.Cuts" user "Board Geometry/Outline")
		(27 "Margin" user)
		(31 "F.CrtYd" user "Package Geometry/Place Bound Top")
		(29 "B.CrtYd" user "Package Geometry/Place Bound Bottom")
		(35 "F.Fab" user "Ref Des/Assembly Top")
		(33 "B.Fab" user "Ref Des/Assembly Bottom")
	)
	(footprint ""
		(layer "F.Cu")
		(at 462.452212 -20.558506 -90)
		(property "Reference" "R869"
			(at 0 0 270)
			(layer "F.SilkS")
			(hide yes)
			(effects
				(font
					(size 1.27 1.27)
				)
			)
		)
		(property "Value" "0R2J-2-GP"
			(at 0.064008 -3.993896 270)
			(unlocked yes)
			(layer "F.Fab")
			(hide yes)
			(effects
				(font
					(size 1.016 1.016)
					(thickness 0.1524)
				)
			)
		)
		(property "Device Type" "R402H16"
			(at 0.064008 -5.517896 270)
			(unlocked yes)
			(layer "F.Fab")
			(hide yes)
			(effects
				(font
					(size 1.016 1.016)
					(thickness 0.1524)
				)
			)
		)
		(duplicate_pad_numbers_are_jumpers no)
		(fp_line
			(start -0.508 -0.9398)
			(end -0.508 0.9398)
			(stroke
				(width 0.1524)
				(type default)
			)
			(layer "F.SilkS")
		)
		(fp_line
			(start 0.508 -0.9398)
			(end -0.508 -0.9398)
			(stroke
				(width 0.1524)
				(type default)
			)
			(layer "F.SilkS")
		)
		(fp_rect
			(start -0.508 0.9398)
			(end 0.508 -0.9398)
			(stroke
				(width 0)
				(type default)
			)
			(fill no)
			(layer "F.CrtYd")
		)
		(fp_rect
			(start -0.508 0.9398)
			(end 0.508 -0.9398)
			(stroke
				(width 0)
				(type default)
			)
			(fill no)
			(layer "F.Fab")
		)
		(pad "1" smd custom
			(at 0 -0.4445 270)
			(size 0.1397 0.1397)
			(layers "F.Cu" "F.Mask" "F.Paste")
			(net "SW_HDD_G34")
			(options
				(clearance outline)
				(anchor circle)
			)
			(primitives
				(gr_poly
					(pts
						(arc
							(start -0.1778 -0.2794)
							(mid -0.249642 -0.249642)
							(end -0.2794 -0.1778)
						)
						(arc
							(start -0.2794 0.1778)
							(mid -0.249642 0.249642)
							(end -0.1778 0.2794)
						)
						(arc
							(start 0.1778 0.2794)
							(mid 0.249642 0.249642)
							(end 0.2794 0.1778)
						)
						(arc
							(start 0.2794 -0.1778)
							(mid 0.249642 -0.249642)
							(end 0.1778 -0.2794)
						)
					)
					(width 0)
					(fill yes)
				)
			)
		)
		(pad "2" smd custom
			(at 0 0.4445 270)
			(size 0.1397 0.1397)
			(layers "F.Cu" "F.Mask" "F.Paste")
			(net "SW_HDD_R34")
			(options
				(clearance outline)
				(anchor circle)
			)
			(primitives
				(gr_poly
					(pts
						(arc
							(start -0.1778 -0.2794)
							(mid -0.249642 -0.249642)
							(end -0.2794 -0.1778)
						)
						(arc
							(start -0.2794 0.1778)
							(mid -0.249642 0.249642)
							(end -0.1778 0.2794)
						)
						(arc
							(start 0.1778 0.2794)
							(mid 0.249642 0.249642)
							(end 0.2794 0.1778)
						)
						(arc
							(start 0.2794 -0.1778)
							(mid 0.249642 -0.249642)
							(end 0.1778 -0.2794)
						)
					)
					(width 0)
					(fill yes)
				)
			)
		)
	)
	(footprint ""
		(layer "F.Cu")
		(at 469.773 -150.622 -90)
		(property "Reference" "C333"
			(at 0 0 270)
			(layer "F.SilkS")
			(hide yes)
			(effects
				(font
					(size 1.27 1.27)
				)
			)
		)
		(property "Value" "SC4D7U25V5KX-1-GP"
			(at -0.0762 -6.1214 270)
			(unlocked yes)
			(layer "F.Fab")
			(hide yes)
			(effects
				(font
					(size 1.016 1.016)
					(thickness 0.1524)
				)
			)
		)
		(property "Device Type" "C805H58"
			(at -0.0762 -8.1534 270)
			(unlocked yes)
			(layer "F.Fab")
			(hide yes)
			(effects
				(font
					(size 1.016 1.016)
					(thickness 0.1524)
				)
			)
		)
		(duplicate_pad_numbers_are_jumpers no)
		(fp_line
			(start 0.635 0)
			(end -0.635 0)
			(stroke
				(width 0.508)
				(type default)
			)
			(layer "F.SilkS")
		)
		(fp_rect
			(start -0.9652 1.778)
			(end 0.9652 -1.778)
			(stroke
				(width 0)
				(type default)
			)
			(fill no)
			(layer "F.CrtYd")
		)
		(fp_poly
			(pts
				(xy -0.9652 -1.778) (xy 0.9652 -1.778) (xy 0.9652 1.778) (xy -0.9652 1.778)
			)
			(stroke
				(width 0)
				(type default)
			)
			(fill no)
			(layer "F.Fab")
		)
		(pad "1" smd rect
			(at 0 -0.9652 270)
			(size 1.397 1.143)
			(layers "F.Cu" "F.Mask" "F.Paste")
			(net "P12V_HDD23")
		)
		(pad "2" smd rect
			(at 0 0.9652 270)
			(size 1.397 1.143)
			(layers "F.Cu" "F.Mask" "F.Paste")
			(net "GND")
		)
	)
	(footprint ""
		(layer "F.Cu")
		(at 166.596568 -214.784178 90)
		(property "Reference" "Q248"
			(at 0 0 90)
			(layer "F.SilkS")
			(hide yes)
			(effects
				(font
					(size 1.27 1.27)
				)
			)
		)
		(property "Value" "SSM3K324R-GP"
			(at 0.127 -8.9662 90)
			(unlocked yes)
			(layer "F.Fab")
			(hide yes)
			(effects
				(font
					(size 1.016 1.016)
					(thickness 0.1524)
				)
			)
		)
		(property "Device Type" "SOT23DGS2D4H35"
			(at 0.127 -10.4902 90)
			(unlocked yes)
			(layer "F.Fab")
			(hide yes)
			(effects
				(font
					(size 1.016 1.016)
					(thickness 0.1524)
				)
			)
		)
		(duplicate_pad_numbers_are_jumpers no)
		(fp_line
			(start 1.651 -1.778)
			(end -1.651 -1.778)
			(stroke
				(width 0.1524)
				(type default)
			)
			(layer "F.SilkS")
		)
		(fp_line
			(start -1.651 -1.778)
			(end -1.651 1.778)
			(stroke
				(width 0.1524)
				(type default)
			)
			(layer "F.SilkS")
		)
		(fp_line
			(start 1.651 1.778)
			(end 1.651 -1.778)
			(stroke
				(width 0.1524)
				(type default)
			)
			(layer "F.SilkS")
		)
		(fp_line
			(start -1.651 1.778)
			(end 1.651 1.778)
			(stroke
				(width 0.1524)
				(type default)
			)
			(layer "F.SilkS")
		)
		(fp_poly
			(pts
				(xy -1.778 1.8796) (xy -1.778 -1.8796) (xy 1.778 -1.8796) (xy 1.778 1.8796)
			)
			(stroke
				(width 0)
				(type default)
			)
			(fill no)
			(layer "F.CrtYd")
		)
		(fp_poly
			(pts
				(xy -1.778 1.8796) (xy -1.778 -1.8796) (xy 1.778 -1.8796) (xy 1.778 1.8796)
			)
			(stroke
				(width 0)
				(type default)
			)
			(fill no)
			(layer "F.Fab")
		)
		(pad "D" smd custom
			(at 0 -0.9525 90)
			(size 0.1905 0.1905)
			(layers "F.Cu" "F.Mask" "F.Paste")
			(net "DRV_ACT_5_N")
			(options
				(clearance outline)
				(anchor circle)
			)
			(primitives
				(gr_poly
					(pts
						(arc
							(start -0.1778 0.5715)
							(mid -0.321484 0.511984)
							(end -0.381 0.3683)
						)
						(arc
							(start -0.381 -0.3683)
							(mid -0.321484 -0.511984)
							(end -0.1778 -0.5715)
						)
						(arc
							(start 0.1778 -0.5715)
							(mid 0.321484 -0.511984)
							(end 0.381 -0.3683)
						)
						(arc
							(start 0.381 0.3683)
							(mid 0.321484 0.511984)
							(end 0.1778 0.5715)
						)
					)
					(width 0)
					(fill yes)
				)
			)
		)
		(pad "G" smd custom
			(at -0.98425 0.9525 90)
			(size 0.1905 0.1905)
			(layers "F.Cu" "F.Mask" "F.Paste")
			(net "DRIVE_B_5_ACT")
			(options
				(clearance outline)
				(anchor circle)
			)
			(primitives
				(gr_poly
					(pts
						(arc
							(start -0.1778 0.5715)
							(mid -0.321484 0.511984)
							(end -0.381 0.3683)
						)
						(arc
							(start -0.381 -0.3683)
							(mid -0.321484 -0.511984)
							(end -0.1778 -0.5715)
						)
						(arc
							(start 0.1778 -0.5715)
							(mid 0.321484 -0.511984)
							(end 0.381 -0.3683)
						)
						(arc
							(start 0.381 0.3683)
							(mid 0.321484 0.511984)
							(end 0.1778 0.5715)
						)
					)
					(width 0)
					(fill yes)
				)
			)
		)
		(pad "S" smd custom
			(at 0.98425 0.9525 90)
			(size 0.1905 0.1905)
			(layers "F.Cu" "F.Mask" "F.Paste")
			(net "GND")
			(options
				(clearance outline)
				(anchor circle)
			)
			(primitives
				(gr_poly
					(pts
						(arc
							(start -0.1778 0.5715)
							(mid -0.321484 0.511984)
							(end -0.381 0.3683)
						)
						(arc
							(start -0.381 -0.3683)
							(mid -0.321484 -0.511984)
							(end -0.1778 -0.5715)
						)
						(arc
							(start 0.1778 -0.5715)
							(mid 0.321484 -0.511984)
							(end 0.381 -0.3683)
						)
						(arc
							(start 0.381 0.3683)
							(mid 0.321484 0.511984)
							(end 0.1778 0.5715)
						)
					)
					(width 0)
					(fill yes)
				)
			)
		)
	)
	(footprint ""
		(layer "F.Cu")
		(at 34.285682 -14.990826 90)
		(property "Reference" "VIA49"
			(at 0 0 90)
			(layer "F.SilkS")
			(hide yes)
			(effects
				(font
					(size 1.27 1.27)
				)
			)
		)
		(property "Value" "100OHM-8L-2D36MM-L18-GP"
			(at 3.8989 0.5715 90)
			(unlocked yes)
			(layer "F.Fab")
			(hide yes)
			(effects
				(font
					(size 1.016 1.016)
					(thickness 0.1524)
				)
			)
		)
		(property "Device Type" "VIA-PCIE-4P-414097"
			(at 3.8989 -0.9525 90)
			(unlocked yes)
			(layer "F.Fab")
			(hide yes)
			(effects
				(font
					(size 1.016 1.016)
					(thickness 0.1524)
				)
			)
		)
		(duplicate_pad_numbers_are_jumpers no)
		(fp_rect
			(start -2.0701 0.4826)
			(end 2.0701 -0.4826)
			(stroke
				(width 0)
				(type default)
			)
			(fill no)
			(layer "F.CrtYd")
		)
		(fp_rect
			(start -2.0701 0.4826)
			(end 2.0701 -0.4826)
			(stroke
				(width 0)
				(type default)
			)
			(fill no)
			(layer "F.Fab")
		)
		(pad "1" thru_hole circle
			(at -1.5875 0 90)
			(size 0.508 0.508)
			(drill 0.254)
			(layers "*.Cu" "*.Mask")
			(remove_unused_layers no)
			(net "GND")
			(clearance 0.2286)
			(thermal_gap 0.2286)
		)
		(pad "2" thru_hole circle
			(at -0.5715 0 90)
			(size 0.508 0.508)
			(drill 0.254)
			(layers "*.Cu" "*.Mask")
			(remove_unused_layers no)
			(net "PHY_SCC_B_TO_DRV_B_24_DP")
			(clearance 0.2286)
			(thermal_gap 0.2286)
		)
		(pad "3" thru_hole circle
			(at 0.5715 0 90)
			(size 0.508 0.508)
			(drill 0.254)
			(layers "*.Cu" "*.Mask")
			(remove_unused_layers no)
			(net "PHY_SCC_B_TO_DRV_B_24_DN")
			(clearance 0.2286)
			(thermal_gap 0.2286)
		)
		(pad "4" thru_hole circle
			(at 1.5875 0 90)
			(size 0.508 0.508)
			(drill 0.254)
			(layers "*.Cu" "*.Mask")
			(remove_unused_layers no)
			(net "GND")
			(clearance 0.2286)
			(thermal_gap 0.2286)
		)
	)
	(footprint ""
		(layer "F.Cu")
		(at 301.371 -225.044 -90)
		(property "Reference" "R6"
			(at 0 0 270)
			(layer "F.SilkS")
			(hide yes)
			(effects
				(font
					(size 1.27 1.27)
				)
			)
		)
		(property "Value" "10KR2F-2-GP"
			(at 0.064008 -3.993896 270)
			(unlocked yes)
			(layer "F.Fab")
			(hide yes)
			(effects
				(font
					(size 1.016 1.016)
					(thickness 0.1524)
				)
			)
		)
		(property "Device Type" "R402H16"
			(at 0.064008 -5.517896 270)
			(unlocked yes)
			(layer "F.Fab")
			(hide yes)
			(effects
				(font
					(size 1.016 1.016)
					(thickness 0.1524)
				)
			)
		)
		(duplicate_pad_numbers_are_jumpers no)
		(fp_line
			(start -0.508 -0.9398)
			(end -0.508 0.9398)
			(stroke
				(width 0.1524)
				(type default)
			)
			(layer "F.SilkS")
		)
		(fp_line
			(start 0.508 -0.9398)
			(end -0.508 -0.9398)
			(stroke
				(width 0.1524)
				(type default)
			)
			(layer "F.SilkS")
		)
		(fp_rect
			(start -0.508 0.9398)
			(end 0.508 -0.9398)
			(stroke
				(width 0)
				(type default)
			)
			(fill no)
			(layer "F.CrtYd")
		)
		(fp_rect
			(start -0.508 0.9398)
			(end 0.508 -0.9398)
			(stroke
				(width 0)
				(type default)
			)
			(fill no)
			(layer "F.Fab")
		)
		(pad "1" smd custom
			(at 0 -0.4445 270)
			(size 0.1397 0.1397)
			(layers "F.Cu" "F.Mask" "F.Paste")
			(net "P3V3_STBY_B")
			(options
				(clearance outline)
				(anchor circle)
			)
			(primitives
				(gr_poly
					(pts
						(arc
							(start -0.1778 -0.2794)
							(mid -0.249642 -0.249642)
							(end -0.2794 -0.1778)
						)
						(arc
							(start -0.2794 0.1778)
							(mid -0.249642 0.249642)
							(end -0.1778 0.2794)
						)
						(arc
							(start 0.1778 0.2794)
							(mid 0.249642 0.249642)
							(end 0.2794 0.1778)
						)
						(arc
							(start 0.2794 -0.1778)
							(mid 0.249642 -0.249642)
							(end 0.1778 -0.2794)
						)
					)
					(width 0)
					(fill yes)
				)
			)
		)
		(pad "2" smd custom
			(at 0 0.4445 270)
			(size 0.1397 0.1397)
			(layers "F.Cu" "F.Mask" "F.Paste")
			(net "SCC_B_TYPE_2")
			(options
				(clearance outline)
				(anchor circle)
			)
			(primitives
				(gr_poly
					(pts
						(arc
							(start -0.1778 -0.2794)
							(mid -0.249642 -0.249642)
							(end -0.2794 -0.1778)
						)
						(arc
							(start -0.2794 0.1778)
							(mid -0.249642 0.249642)
							(end -0.1778 0.2794)
						)
						(arc
							(start 0.1778 0.2794)
							(mid 0.249642 0.249642)
							(end 0.2794 0.1778)
						)
						(arc
							(start 0.2794 -0.1778)
							(mid 0.249642 -0.249642)
							(end 0.1778 -0.2794)
						)
					)
					(width 0)
					(fill yes)
				)
			)
		)
	)
	(footprint ""
		(layer "F.Cu")
		(at 55.499 -157.226)
		(property "Reference" "C204"
			(at 0 0 0)
			(layer "F.SilkS")
			(hide yes)
			(effects
				(font
					(size 1.27 1.27)
				)
			)
		)
		(property "Value" "SC4D7U25V5KX-1-GP"
			(at -0.0762 -6.1214 0)
			(unlocked yes)
			(layer "F.Fab")
			(hide yes)
			(effects
				(font
					(size 1.016 1.016)
					(thickness 0.1524)
				)
			)
		)
		(property "Device Type" "C805H58"
			(at -0.0762 -8.1534 0)
			(unlocked yes)
			(layer "F.Fab")
			(hide yes)
			(effects
				(font
					(size 1.016 1.016)
					(thickness 0.1524)
				)
			)
		)
		(duplicate_pad_numbers_are_jumpers no)
		(fp_line
			(start 0.635 0)
			(end -0.635 0)
			(stroke
				(width 0.508)
				(type default)
			)
			(layer "F.SilkS")
		)
		(fp_rect
			(start -0.9652 1.778)
			(end 0.9652 -1.778)
			(stroke
				(width 0)
				(type default)
			)
			(fill no)
			(layer "F.CrtYd")
		)
		(fp_poly
			(pts
				(xy -0.9652 -1.778) (xy 0.9652 -1.778) (xy 0.9652 1.778) (xy -0.9652 1.778)
			)
			(stroke
				(width 0)
				(type default)
			)
			(fill no)
			(layer "F.Fab")
		)
		(pad "1" smd rect
			(at 0 -0.9652)
			(size 1.397 1.143)
			(layers "F.Cu" "F.Mask" "F.Paste")
			(net "P12V_HDD13")
		)
		(pad "2" smd rect
			(at 0 0.9652)
			(size 1.397 1.143)
			(layers "F.Cu" "F.Mask" "F.Paste")
			(net "GND")
		)
	)
	(footprint ""
		(layer "F.Cu")
		(at 113.538 -265.684 90)
		(property "Reference" "R208"
			(at 0 0 90)
			(layer "F.SilkS")
			(hide yes)
			(effects
				(font
					(size 1.27 1.27)
				)
			)
		)
		(property "Value" "2R6F-GP"
			(at -0.0508 -4.8514 90)
			(unlocked yes)
			(layer "F.Fab")
			(hide yes)
			(effects
				(font
					(size 1.016 1.016)
					(thickness 0.1524)
				)
			)
		)
		(property "Device Type" "R1206H26"
			(at 0 -6.3754 90)
			(unlocked yes)
			(layer "F.Fab")
			(hide yes)
			(effects
				(font
					(size 1.016 1.016)
					(thickness 0.1524)
				)
			)
		)
		(duplicate_pad_numbers_are_jumpers no)
		(fp_line
			(start 1.016 -2.2352)
			(end 1.016 2.2352)
			(stroke
				(width 0.1524)
				(type default)
			)
			(layer "F.SilkS")
		)
		(fp_line
			(start -1.016 -2.2352)
			(end 1.016 -2.2352)
			(stroke
				(width 0.1524)
				(type default)
			)
			(layer "F.SilkS")
		)
		(fp_line
			(start 1.016 2.2352)
			(end -1.016 2.2352)
			(stroke
				(width 0.1524)
				(type default)
			)
			(layer "F.SilkS")
		)
		(fp_line
			(start -1.016 2.2352)
			(end -1.016 -2.2352)
			(stroke
				(width 0.1524)
				(type default)
			)
			(layer "F.SilkS")
		)
		(fp_rect
			(start -1.0922 2.3114)
			(end 1.0922 -2.3114)
			(stroke
				(width 0)
				(type default)
			)
			(fill no)
			(layer "F.CrtYd")
		)
		(fp_poly
			(pts
				(xy -1.0922 -2.3114) (xy 1.0922 -2.3114) (xy 1.0922 2.3114) (xy -1.0922 2.3114)
			)
			(stroke
				(width 0)
				(type default)
			)
			(fill no)
			(layer "F.Fab")
		)
		(pad "1" smd rect
			(at 0 -1.397 90)
			(size 1.651 1.27)
			(layers "F.Cu" "F.Mask" "F.Paste")
			(net "P12V_HDD3")
		)
		(pad "2" smd rect
			(at 0 1.397 90)
			(size 1.651 1.27)
			(layers "F.Cu" "F.Mask" "F.Paste")
			(net "12V_PRE_3")
		)
	)
	(footprint ""
		(layer "F.Cu")
		(at 326.738996 -375.92 90)
		(property "Reference" "R944"
			(at 0 0 90)
			(layer "F.SilkS")
			(hide yes)
			(effects
				(font
					(size 1.27 1.27)
				)
			)
		)
		(property "Value" "100KR2F-L1-GP"
			(at 0.064008 -3.993896 90)
			(unlocked yes)
			(layer "F.Fab")
			(hide yes)
			(effects
				(font
					(size 1.016 1.016)
					(thickness 0.1524)
				)
			)
		)
		(property "Device Type" "R402H16"
			(at 0.064008 -5.517896 90)
			(unlocked yes)
			(layer "F.Fab")
			(hide yes)
			(effects
				(font
					(size 1.016 1.016)
					(thickness 0.1524)
				)
			)
		)
		(duplicate_pad_numbers_are_jumpers no)
		(fp_line
			(start 0.508 -0.9398)
			(end -0.508 -0.9398)
			(stroke
				(width 0.1524)
				(type default)
			)
			(layer "F.SilkS")
		)
		(fp_line
			(start -0.508 -0.9398)
			(end -0.508 0.9398)
			(stroke
				(width 0.1524)
				(type default)
			)
			(layer "F.SilkS")
		)
		(fp_rect
			(start -0.508 0.9398)
			(end 0.508 -0.9398)
			(stroke
				(width 0)
				(type default)
			)
			(fill no)
			(layer "F.CrtYd")
		)
		(fp_rect
			(start -0.508 0.9398)
			(end 0.508 -0.9398)
			(stroke
				(width 0)
				(type default)
			)
			(fill no)
			(layer "F.Fab")
		)
		(pad "1" smd custom
			(at 0 -0.4445 90)
			(size 0.1397 0.1397)
			(layers "F.Cu" "F.Mask" "F.Paste")
			(net "P3V3_IN")
			(options
				(clearance outline)
				(anchor circle)
			)
			(primitives
				(gr_poly
					(pts
						(arc
							(start -0.1778 -0.2794)
							(mid -0.249642 -0.249642)
							(end -0.2794 -0.1778)
						)
						(arc
							(start -0.2794 0.1778)
							(mid -0.249642 0.249642)
							(end -0.1778 0.2794)
						)
						(arc
							(start 0.1778 0.2794)
							(mid 0.249642 0.249642)
							(end 0.2794 0.1778)
						)
						(arc
							(start 0.2794 -0.1778)
							(mid 0.249642 -0.249642)
							(end 0.1778 -0.2794)
						)
					)
					(width 0)
					(fill yes)
				)
			)
		)
		(pad "2" smd custom
			(at 0 0.4445 90)
			(size 0.1397 0.1397)
			(layers "F.Cu" "F.Mask" "F.Paste")
			(net "FAN_2_INS_N")
			(options
				(clearance outline)
				(anchor circle)
			)
			(primitives
				(gr_poly
					(pts
						(arc
							(start -0.1778 -0.2794)
							(mid -0.249642 -0.249642)
							(end -0.2794 -0.1778)
						)
						(arc
							(start -0.2794 0.1778)
							(mid -0.249642 0.249642)
							(end -0.1778 0.2794)
						)
						(arc
							(start 0.1778 0.2794)
							(mid 0.249642 0.249642)
							(end 0.2794 0.1778)
						)
						(arc
							(start 0.2794 -0.1778)
							(mid 0.249642 -0.249642)
							(end 0.1778 -0.2794)
						)
					)
					(width 0)
					(fill yes)
				)
			)
		)
	)
)
